# TIMECARD (Time Appliance Project (Time Card)) — schematic netlist excerpt (pin names and nets, part order shuffled) for the footprints in the layout excerpt that follows; sources: Cadence DE-HDL packaged netlist, KiCad conversion of R4006-B0001-02_R01.brd

C163  CAPACITOR  4.7UF 6.3V 20%  pkg SMC_0402R_H026  page 14 : \1\ = XP3R3V_FPGA ; \2\ = SG
R413  RESISTOR  1KOHM 1%  pkg SMC_0402R_H016  page 17 : \1\ = UNNAMED_6_LM75BDPTSSOP8_I59_A1 ; \2\ = SG

(kicad_pcb
	(version 20260206)
	(generator "pcbnew")
	(generator_version "10.0")
	(general
		(thickness 1.6)
		(legacy_teardrops no)
	)
	(paper "A4")
	(title_block
		(title "timecard-production-celestica-r4006 — R4006-B0001-02_R01.brd")
		(comment 1 "Time Appliance Project (Time Card) / footprints 696-697 of 1113")
	)
	(layers
		(0 "F.Cu" signal "TOP")
		(4 "In1.Cu" signal "L02_GND1")
		(6 "In2.Cu" signal "L03_SIG1")
		(8 "In3.Cu" signal "L04_GND2")
		(10 "In4.Cu" signal "L05_VCC1")
		(12 "In5.Cu" signal "L06_VCC2")
		(14 "In6.Cu" signal "L07_GND3")
		(16 "In7.Cu" signal "L08_SIG2")
		(18 "In8.Cu" signal "L09_GND4")
		(2 "B.Cu" signal "BOTTOM")
		(9 "F.Adhes" user "F.Adhesive")
		(11 "B.Adhes" user "B.Adhesive")
		(13 "F.Paste" user "Package Geometry/Pastemask Top")
		(15 "B.Paste" user "Package Geometry/Pastemask Bottom")
		(5 "F.SilkS" user "Ref Des/Silkscreen Top")
		(7 "B.SilkS" user "Ref Des/Silkscreen Bottom")
		(1 "F.Mask" user "Board Geometry/Soldermask Top")
		(3 "B.Mask" user "Board Geometry/Soldermask Bottom")
		(17 "Dwgs.User" user "User.Drawings")
		(19 "Cmts.User" user "User.Comments")
		(21 "Eco1.User" user "User.Eco1")
		(23 "Eco2.User" user "User.Eco2")
		(25 "Edge.Cuts" user "Board Geometry/Outline")
		(27 "Margin" user)
		(31 "F.CrtYd" user "Package Geometry/Place Bound Top")
		(29 "B.CrtYd" user "Package Geometry/Place Bound Bottom")
		(35 "F.Fab" user "Ref Des/Assembly Top")
		(33 "B.Fab" user "Ref Des/Assembly Bottom")
	)
	(footprint ""
		(layer "B.Cu")
		(at 113.68659 -56.388)
		(property "Reference" "C163"
			(at 1.59766 -0.635 270)
			(unlocked yes)
			(layer "B.SilkS")
			(effects
				(font
					(size 0.635 0.4064)
					(thickness 0.1524)
				)
				(justify mirror)
			)
		)
		(property "Value" "VAL*"
			(at -0.02032 2.13233 0)
			(unlocked yes)
			(layer "B.Fab")
			(hide yes)
			(effects
				(font
					(size 0.7874 0.5842)
					(thickness 0.1524)
				)
				(justify mirror)
			)
		)
		(property "Device Type" "CAPACITOR-G105-0F475-BM,4.7UF,A"
			(at -0.008382 1.210564 0)
			(unlocked yes)
			(layer "B.Fab")
			(hide yes)
			(effects
				(font
					(size 0.7874 0.5842)
					(thickness 0.1524)
				)
				(justify mirror)
			)
		)
		(property "User Part Number" "PARTNUM*"
			(at -0.02032 4.024884 0)
			(unlocked yes)
			(layer "Cmts.User")
			(hide yes)
			(effects
				(font
					(size 0.7874 0.5842)
					(thickness 0.1524)
				)
				(justify mirror)
			)
		)
		(property "Tolerance" "TOL*"
			(at -0.044704 3.05435 0)
			(unlocked yes)
			(layer "Cmts.User")
			(hide yes)
			(effects
				(font
					(size 0.7874 0.5842)
					(thickness 0.1524)
				)
				(justify mirror)
			)
		)
		(duplicate_pad_numbers_are_jumpers no)
		(fp_line
			(start -1.143 -0.5588)
			(end 1.143 -0.5588)
			(stroke
				(width 0.1)
				(type default)
			)
			(layer "B.SilkS")
		)
		(fp_line
			(start -1.143 0.5588)
			(end -1.143 -0.5588)
			(stroke
				(width 0.1)
				(type default)
			)
			(layer "B.SilkS")
		)
		(fp_line
			(start 1.143 -0.5588)
			(end 1.143 0.5588)
			(stroke
				(width 0.1)
				(type default)
			)
			(layer "B.SilkS")
		)
		(fp_line
			(start 1.143 0.5588)
			(end -1.143 0.5588)
			(stroke
				(width 0.1)
				(type default)
			)
			(layer "B.SilkS")
		)
		(fp_rect
			(start -1.143 0.5588)
			(end 1.143 -0.5588)
			(stroke
				(width 0)
				(type default)
			)
			(fill no)
			(layer "B.CrtYd")
		)
		(fp_line
			(start -0.508 -0.3048)
			(end 0.508 -0.3048)
			(stroke
				(width 0.1)
				(type default)
			)
			(layer "B.Fab")
		)
		(fp_line
			(start -0.508 0.3048)
			(end -0.508 -0.3048)
			(stroke
				(width 0.1)
				(type default)
			)
			(layer "B.Fab")
		)
		(fp_line
			(start 0.508 -0.3048)
			(end 0.508 0.3048)
			(stroke
				(width 0.1)
				(type default)
			)
			(layer "B.Fab")
		)
		(fp_line
			(start 0.508 0.3048)
			(end -0.508 0.3048)
			(stroke
				(width 0.1)
				(type default)
			)
			(layer "B.Fab")
		)
		(pad "1" smd rect
			(at 0.5334 0 180)
			(size 0.7112 0.6096)
			(layers "B.Cu" "B.Mask" "B.Paste")
			(net "XP3R3V_FPGA")
		)
		(pad "2" smd rect
			(at -0.5334 0 180)
			(size 0.7112 0.6096)
			(layers "B.Cu" "B.Mask" "B.Paste")
			(net "SG")
		)
		(zone
			(layer "B.Cu")
			(hatch none 0.5)
			(connect_pads
				(clearance 0)
			)
			(min_thickness 0.25)
			(keepout
				(tracks allowed)
				(vias not_allowed)
				(pads allowed)
				(copperpour not_allowed)
				(footprints allowed)
			)
			(placement
				(enabled no)
				(sheetname "")
			)
			(fill
				(thermal_gap 0.5)
				(thermal_bridge_width 0.5)
				(island_removal_mode 0)
			)
			(polygon
				(pts
					(xy 113.61039 -56.0832) (xy 113.76279 -56.0832) (xy 113.76279 -56.6928) (xy 113.61039 -56.6928)
				)
			)
		)
	)
	(footprint ""
		(layer "B.Cu")
		(at 54.0512 -74.9808 90)
		(property "Reference" "R413"
			(at 4.064 0.08763 270)
			(unlocked yes)
			(layer "B.SilkS")
			(effects
				(font
					(size 0.7874 0.5842)
					(thickness 0.1524)
				)
				(justify mirror)
			)
		)
		(property "Value" "VAL*"
			(at -0.02032 2.13233 90)
			(unlocked yes)
			(layer "B.Fab")
			(hide yes)
			(effects
				(font
					(size 0.7874 0.5842)
					(thickness 0.1524)
				)
				(justify mirror)
			)
		)
		(property "Device Type" "RESISTOR-G155-11001-01,1KOHM,1%"
			(at -0.008382 1.210564 90)
			(unlocked yes)
			(layer "B.Fab")
			(hide yes)
			(effects
				(font
					(size 0.7874 0.5842)
					(thickness 0.1524)
				)
				(justify mirror)
			)
		)
		(property "User Part Number" "PARTNUM*"
			(at -0.02032 4.024884 90)
			(unlocked yes)
			(layer "Cmts.User")
			(hide yes)
			(effects
				(font
					(size 0.7874 0.5842)
					(thickness 0.1524)
				)
				(justify mirror)
			)
		)
		(property "Tolerance" "TOL*"
			(at -0.044704 3.05435 90)
			(unlocked yes)
			(layer "Cmts.User")
			(hide yes)
			(effects
				(font
					(size 0.7874 0.5842)
					(thickness 0.1524)
				)
				(justify mirror)
			)
		)
		(duplicate_pad_numbers_are_jumpers no)
		(fp_line
			(start 1.143 -0.5588)
			(end 1.143 0.5588)
			(stroke
				(width 0.1)
				(type default)
			)
			(layer "B.SilkS")
		)
		(fp_line
			(start -1.143 -0.5588)
			(end 1.143 -0.5588)
			(stroke
				(width 0.1)
				(type default)
			)
			(layer "B.SilkS")
		)
		(fp_line
			(start 1.143 0.5588)
			(end -1.143 0.5588)
			(stroke
				(width 0.1)
				(type default)
			)
			(layer "B.SilkS")
		)
		(fp_line
			(start -1.143 0.5588)
			(end -1.143 -0.5588)
			(stroke
				(width 0.1)
				(type default)
			)
			(layer "B.SilkS")
		)
		(fp_rect
			(start 1.143 0.5588)
			(end -1.143 -0.5588)
			(stroke
				(width 0)
				(type default)
			)
			(fill no)
			(layer "B.CrtYd")
		)
		(fp_line
			(start 0.508 -0.3048)
			(end 0.508 0.3048)
			(stroke
				(width 0.1)
				(type default)
			)
			(layer "B.Fab")
		)
		(fp_line
			(start -0.508 -0.3048)
			(end 0.508 -0.3048)
			(stroke
				(width 0.1)
				(type default)
			)
			(layer "B.Fab")
		)
		(fp_line
			(start 0.508 0.3048)
			(end -0.508 0.3048)
			(stroke
				(width 0.1)
				(type default)
			)
			(layer "B.Fab")
		)
		(fp_line
			(start -0.508 0.3048)
			(end -0.508 -0.3048)
			(stroke
				(width 0.1)
				(type default)
			)
			(layer "B.Fab")
		)
		(pad "1" smd rect
			(at 0.5334 0 270)
			(size 0.7112 0.6096)
			(layers "B.Cu" "B.Mask" "B.Paste")
			(net "UNNAMED_6_LM75BDPTSSOP8_I59_A1")
		)
		(pad "2" smd rect
			(at -0.5334 0 270)
			(size 0.7112 0.6096)
			(layers "B.Cu" "B.Mask" "B.Paste")
			(net "SG")
		)
		(zone
			(layer "B.Cu")
			(hatch none 0.5)
			(connect_pads
				(clearance 0)
			)
			(min_thickness 0.25)
			(keepout
				(tracks not_allowed)
				(vias allowed)
				(pads allowed)
				(copperpour not_allowed)
				(footprints allowed)
			)
			(placement
				(enabled no)
				(sheetname "")
			)
			(fill
				(thermal_gap 0.5)
				(thermal_bridge_width 0.5)
				(island_removal_mode 0)
			)
			(polygon
				(pts
					(xy 54.356 -75.057) (xy 53.7464 -75.057) (xy 53.7464 -74.9046) (xy 54.356 -74.9046)
				)
			)
		)
		(zone
			(layer "B.Cu")
			(hatch none 0.5)
			(connect_pads
				(clearance 0)
			)
			(min_thickness 0.25)
			(keepout
				(tracks allowed)
				(vias not_allowed)
				(pads allowed)
				(copperpour not_allowed)
				(footprints allowed)
			)
			(placement
				(enabled no)
				(sheetname "")
			)
			(fill
				(thermal_gap 0.5)
				(thermal_bridge_width 0.5)
				(island_removal_mode 0)
			)
			(polygon
				(pts
					(xy 54.356 -75.057) (xy 53.7464 -75.057) (xy 53.7464 -74.9046) (xy 54.356 -74.9046)
				)
			)
		)
	)
)
